# T6G (Grand Teton) — schematic netlist excerpt (pin names and nets, part order shuffled) for the footprints in the layout excerpt that follows; sources: Cadence DE-HDL packaged netlist, KiCad conversion of 04192023_DAF0TMB3IC0_F0TG_MB_C_brd_V02_OCP.brd

C2124  Q_CAP  22UF 4V 20% X6S  pkg C0402  page 74 : A = PVDD11_S3_P1 ; B = GND
C2419  Q_CAP  22UF 4V 20% X6S  pkg C0402  page 74 : A = PVDDCR_SOC_P1 ; B = GND

(kicad_pcb
	(version 20260206)
	(generator "pcbnew")
	(generator_version "10.0")
	(general
		(thickness 1.6)
		(legacy_teardrops no)
	)
	(paper "A4")
	(title_block
		(title "04192023_DAF0TMB3IC0_F0TG_MB_C_brd_V02_OCP.brd")
		(comment 1 "Grand Teton / footprints 6156-6157 of 8354")
	)
	(layers
		(0 "F.Cu" signal "TOP")
		(4 "In1.Cu" signal "GND")
		(6 "In2.Cu" signal "IN1")
		(8 "In3.Cu" signal "GND1")
		(10 "In4.Cu" signal "IN2")
		(12 "In5.Cu" signal "GND2")
		(14 "In6.Cu" signal "IN3")
		(16 "In7.Cu" signal "GND3")
		(18 "In8.Cu" signal "VCC")
		(20 "In9.Cu" signal "VCC1")
		(22 "In10.Cu" signal "GND4")
		(24 "In11.Cu" signal "IN4")
		(26 "In12.Cu" signal "GND5")
		(28 "In13.Cu" signal "IN5")
		(30 "In14.Cu" signal "GND6")
		(32 "In15.Cu" signal "IN6")
		(34 "In16.Cu" signal "GND7")
		(2 "B.Cu" signal "BOTTOM")
		(9 "F.Adhes" user "F.Adhesive")
		(11 "B.Adhes" user "B.Adhesive")
		(13 "F.Paste" user "Package Geometry/Pastemask Top")
		(15 "B.Paste" user "Package Geometry/Pastemask Bottom")
		(5 "F.SilkS" user "Ref Des/Silkscreen Top")
		(7 "B.SilkS" user "Ref Des/Silkscreen Bottom")
		(1 "F.Mask" user "Board Geometry/Soldermask Top")
		(3 "B.Mask" user "Board Geometry/Soldermask Bottom")
		(17 "Dwgs.User" user "User.Drawings")
		(19 "Cmts.User" user "User.Comments")
		(21 "Eco1.User" user "User.Eco1")
		(23 "Eco2.User" user "User.Eco2")
		(25 "Edge.Cuts" user "Board Geometry/Outline")
		(27 "Margin" user)
		(31 "F.CrtYd" user "Package Geometry/Place Bound Top")
		(29 "B.CrtYd" user "Package Geometry/Place Bound Bottom")
		(35 "F.Fab" user "Ref Des/Assembly Top")
		(33 "B.Fab" user "Ref Des/Assembly Bottom")
	)
	(footprint ""
		(layer "B.Cu")
		(at 111.781336 -254.448564 180)
		(property "Reference" "C2419"
			(at 0 0 0)
			(layer "B.SilkS")
			(hide yes)
			(effects
				(font
					(size 1.27 1.27)
				)
				(justify mirror)
			)
		)
		(property "Value" ""
			(at 0 0 0)
			(layer "B.Fab")
			(effects
				(font
					(size 1.27 1.27)
				)
				(justify mirror)
			)
		)
		(duplicate_pad_numbers_are_jumpers no)
		(fp_line
			(start 0.7874 0.4064)
			(end 0.7874 -0.4064)
			(stroke
				(width 0.1524)
				(type default)
			)
			(layer "B.SilkS")
		)
		(fp_line
			(start 0.7874 -0.4064)
			(end -0.7874 -0.4064)
			(stroke
				(width 0.1524)
				(type default)
			)
			(layer "B.SilkS")
		)
		(fp_line
			(start -0.7874 0.4064)
			(end 0.7874 0.4064)
			(stroke
				(width 0.1524)
				(type default)
			)
			(layer "B.SilkS")
		)
		(fp_line
			(start -0.7874 -0.4064)
			(end -0.7874 0.4064)
			(stroke
				(width 0.1524)
				(type default)
			)
			(layer "B.SilkS")
		)
		(fp_line
			(start 0.67945 0.3048)
			(end 0.67945 -0.305054)
			(stroke
				(width 0.1)
				(type default)
			)
			(layer "B.Fab")
		)
		(fp_line
			(start 0.67945 -0.305054)
			(end 0.12065 -0.305054)
			(stroke
				(width 0.1)
				(type default)
			)
			(layer "B.Fab")
		)
		(fp_line
			(start 0.12065 0.3048)
			(end 0.67945 0.3048)
			(stroke
				(width 0.1)
				(type default)
			)
			(layer "B.Fab")
		)
		(fp_line
			(start 0.12065 0.2794)
			(end 0.12065 0.3048)
			(stroke
				(width 0.1)
				(type default)
			)
			(layer "B.Fab")
		)
		(fp_line
			(start 0.12065 -0.2794)
			(end -0.12065 -0.2794)
			(stroke
				(width 0.1)
				(type default)
			)
			(layer "B.Fab")
		)
		(fp_line
			(start 0.12065 -0.305054)
			(end 0.12065 -0.2794)
			(stroke
				(width 0.1)
				(type default)
			)
			(layer "B.Fab")
		)
		(fp_line
			(start -0.120396 0.3048)
			(end -0.120396 0.2794)
			(stroke
				(width 0.1)
				(type default)
			)
			(layer "B.Fab")
		)
		(fp_line
			(start -0.120396 0.2794)
			(end 0.12065 0.2794)
			(stroke
				(width 0.1)
				(type default)
			)
			(layer "B.Fab")
		)
		(fp_line
			(start -0.12065 -0.2794)
			(end -0.12065 -0.3048)
			(stroke
				(width 0.1)
				(type default)
			)
			(layer "B.Fab")
		)
		(fp_line
			(start -0.12065 -0.3048)
			(end -0.67945 -0.3048)
			(stroke
				(width 0.1)
				(type default)
			)
			(layer "B.Fab")
		)
		(fp_line
			(start -0.67945 0.3048)
			(end -0.120396 0.3048)
			(stroke
				(width 0.1)
				(type default)
			)
			(layer "B.Fab")
		)
		(fp_line
			(start -0.67945 -0.3048)
			(end -0.67945 0.3048)
			(stroke
				(width 0.1)
				(type default)
			)
			(layer "B.Fab")
		)
		(pad "1" smd circle
			(at 0.40005 0)
			(size 0 0)
			(layers "B.Cu" "B.Mask" "B.Paste")
			(net "PVDDCR_SOC_P1")
		)
		(pad "2" smd circle
			(at -0.40005 0)
			(size 0 0)
			(layers "B.Cu" "B.Mask" "B.Paste")
			(net "GND")
		)
	)
	(footprint ""
		(layer "B.Cu")
		(at 110.527084 -261.748016 90)
		(property "Reference" "C2124"
			(at 0 0 90)
			(layer "B.SilkS")
			(hide yes)
			(effects
				(font
					(size 1.27 1.27)
				)
				(justify mirror)
			)
		)
		(property "Value" ""
			(at 0 0 90)
			(layer "B.Fab")
			(effects
				(font
					(size 1.27 1.27)
				)
				(justify mirror)
			)
		)
		(duplicate_pad_numbers_are_jumpers no)
		(fp_line
			(start 0.7874 -0.4064)
			(end -0.7874 -0.4064)
			(stroke
				(width 0.1524)
				(type default)
			)
			(layer "B.SilkS")
		)
		(fp_line
			(start -0.7874 -0.4064)
			(end -0.7874 0.4064)
			(stroke
				(width 0.1524)
				(type default)
			)
			(layer "B.SilkS")
		)
		(fp_line
			(start 0.7874 0.4064)
			(end 0.7874 -0.4064)
			(stroke
				(width 0.1524)
				(type default)
			)
			(layer "B.SilkS")
		)
		(fp_line
			(start -0.7874 0.4064)
			(end 0.7874 0.4064)
			(stroke
				(width 0.1524)
				(type default)
			)
			(layer "B.SilkS")
		)
		(fp_line
			(start 0.67945 -0.305054)
			(end 0.12065 -0.305054)
			(stroke
				(width 0.1)
				(type default)
			)
			(layer "B.Fab")
		)
		(fp_line
			(start 0.12065 -0.305054)
			(end 0.12065 -0.2794)
			(stroke
				(width 0.1)
				(type default)
			)
			(layer "B.Fab")
		)
		(fp_line
			(start -0.12065 -0.3048)
			(end -0.67945 -0.3048)
			(stroke
				(width 0.1)
				(type default)
			)
			(layer "B.Fab")
		)
		(fp_line
			(start -0.67945 -0.3048)
			(end -0.67945 0.3048)
			(stroke
				(width 0.1)
				(type default)
			)
			(layer "B.Fab")
		)
		(fp_line
			(start 0.12065 -0.2794)
			(end -0.12065 -0.2794)
			(stroke
				(width 0.1)
				(type default)
			)
			(layer "B.Fab")
		)
		(fp_line
			(start -0.12065 -0.2794)
			(end -0.12065 -0.3048)
			(stroke
				(width 0.1)
				(type default)
			)
			(layer "B.Fab")
		)
		(fp_line
			(start 0.12065 0.2794)
			(end 0.12065 0.3048)
			(stroke
				(width 0.1)
				(type default)
			)
			(layer "B.Fab")
		)
		(fp_line
			(start -0.120396 0.2794)
			(end 0.12065 0.2794)
			(stroke
				(width 0.1)
				(type default)
			)
			(layer "B.Fab")
		)
		(fp_line
			(start 0.67945 0.3048)
			(end 0.67945 -0.305054)
			(stroke
				(width 0.1)
				(type default)
			)
			(layer "B.Fab")
		)
		(fp_line
			(start 0.12065 0.3048)
			(end 0.67945 0.3048)
			(stroke
				(width 0.1)
				(type default)
			)
			(layer "B.Fab")
		)
		(fp_line
			(start -0.120396 0.3048)
			(end -0.120396 0.2794)
			(stroke
				(width 0.1)
				(type default)
			)
			(layer "B.Fab")
		)
		(fp_line
			(start -0.67945 0.3048)
			(end -0.120396 0.3048)
			(stroke
				(width 0.1)
				(type default)
			)
			(layer "B.Fab")
		)
		(pad "1" smd circle
			(at 0.40005 0 270)
			(size 0 0)
			(layers "B.Cu" "B.Mask" "B.Paste")
			(net "PVDD11_S3_P1")
		)
		(pad "2" smd circle
			(at -0.40005 0 270)
			(size 0 0)
			(layers "B.Cu" "B.Mask" "B.Paste")
			(net "GND")
		)
	)
)
